(kicad_pcb
	(version 20260206)
	(generator "pcbnew")
	(generator_version "10.0")
	(general
		(thickness 1.6)
		(legacy_teardrops no)
	)
	(paper "A4")
	(title_block
		(title "Bryce Canyon_F.DPB_16315-1-OCP.brd")
		(comment 1 "Bryce Canyon / footprints 1842-1844 of 2223")
	)
	(layers
		(0 "F.Cu" signal "TOP")
		(4 "In1.Cu" signal "L2GND")
		(6 "In2.Cu" signal "L3")
		(8 "In3.Cu" signal "L4GND")
		(10 "In4.Cu" signal "L5")
		(12 "In5.Cu" signal "L6VCC")
		(14 "In6.Cu" signal "L7VCC")
		(16 "In7.Cu" signal "L8")
		(18 "In8.Cu" signal "L9GND")
		(20 "In9.Cu" signal "L10")
		(22 "In10.Cu" signal "L11GND")
		(2 "B.Cu" signal "BOTTOM")
		(9 "F.Adhes" user "F.Adhesive")
		(11 "B.Adhes" user "B.Adhesive")
		(13 "F.Paste" user "Package Geometry/Pastemask Top")
		(15 "B.Paste" user "Package Geometry/Pastemask Bottom")
		(5 "F.SilkS" user "Ref Des/Silkscreen Top")
		(7 "B.SilkS" user "Ref Des/Silkscreen Bottom")
		(1 "F.Mask" user "Board Geometry/Soldermask Top")
		(3 "B.Mask" user "Board Geometry/Soldermask Bottom")
		(17 "Dwgs.User" user "User.Drawings")
		(19 "Cmts.User" user "User.Comments")
		(21 "Eco1.User" user "User.Eco1")
		(23 "Eco2.User" user "User.Eco2")
		(25 "Edge.Cuts" user "Board Geometry/Outline")
		(27 "Margin" user)
		(31 "F.CrtYd" user "Package Geometry/Place Bound Top")
		(29 "B.CrtYd" user "Package Geometry/Place Bound Bottom")
		(35 "F.Fab" user "Ref Des/Assembly Top")
		(33 "B.Fab" user "Ref Des/Assembly Bottom")
	)
	(footprint ""
		(layer "F.Cu")
		(at 357.100124 -57.909968 -90)
		(property "Reference" "HDDSAS31"
			(at 0 0 270)
			(layer "F.SilkS")
			(hide yes)
			(effects
				(font
					(size 1.27 1.27)
				)
			)
		)
		(property "Value" "SKT-SAS15P-14P-45-GP"
			(at -20.7645 -8.9789 270)
			(unlocked yes)
			(layer "F.Fab")
			(hide yes)
			(effects
				(font
					(size 1.016 1.016)
					(thickness 0.1524)
				)
			)
		)
		(property "Device Type" "10120818-001C-TRLF"
			(at -20.7645 -10.5029 270)
			(unlocked yes)
			(layer "F.Fab")
			(hide yes)
			(effects
				(font
					(size 1.016 1.016)
					(thickness 0.1524)
				)
			)
		)
		(duplicate_pad_numbers_are_jumpers no)
		(fp_line
			(start 1.651 4.2926)
			(end 1.651 3.0099)
			(stroke
				(width 0.1524)
				(type default)
			)
			(layer "F.SilkS")
		)
		(fp_line
			(start 8.509 4.2926)
			(end 1.651 4.2926)
			(stroke
				(width 0.1524)
				(type default)
			)
			(layer "F.SilkS")
		)
		(fp_line
			(start -23.4188 3.0099)
			(end -23.4188 -3.2512)
			(stroke
				(width 0.1524)
				(type default)
			)
			(layer "F.SilkS")
		)
		(fp_line
			(start 1.651 3.0099)
			(end -23.4188 3.0099)
			(stroke
				(width 0.1524)
				(type default)
			)
			(layer "F.SilkS")
		)
		(fp_line
			(start 8.509 3.0099)
			(end 8.509 4.2926)
			(stroke
				(width 0.1524)
				(type default)
			)
			(layer "F.SilkS")
		)
		(fp_line
			(start 23.4188 3.0099)
			(end 8.509 3.0099)
			(stroke
				(width 0.1524)
				(type default)
			)
			(layer "F.SilkS")
		)
		(fp_line
			(start -23.4188 -3.2512)
			(end 23.4188 -3.2512)
			(stroke
				(width 0.1524)
				(type default)
			)
			(layer "F.SilkS")
		)
		(fp_line
			(start 23.4188 -3.2512)
			(end 23.4188 3.0099)
			(stroke
				(width 0.1524)
				(type default)
			)
			(layer "F.SilkS")
		)
		(fp_line
			(start 15.5067 -3.3401)
			(end 16.2687 -3.3401)
			(stroke
				(width 0.3302)
				(type default)
			)
			(layer "F.SilkS")
		)
		(fp_poly
			(pts
				(xy 15.868904 -3.230372) (xy 16.503904 -3.865372) (xy 15.233904 -3.865372)
			)
			(stroke
				(width 0)
				(type default)
			)
			(fill yes)
			(layer "F.SilkS")
		)
		(fp_poly
			(pts
				(xy -22.8727 -2.7559) (xy 22.8727 -2.7559) (xy 22.8727 2.7559) (xy 8.255 2.7559) (xy 8.255 3.5179)
				(xy 1.905 3.5179) (xy 1.905 2.7559) (xy -22.8727 2.7559)
			)
			(stroke
				(width 0)
				(type default)
			)
			(fill no)
			(layer "F.CrtYd")
		)
		(fp_poly
			(pts
				(xy 1.397 4.5466) (xy 1.397 3.2639) (xy -23.6728 3.2639) (xy -23.6728 -3.5052) (xy 23.6728 -3.5052)
				(xy 23.6728 -0.00635) (xy 22.8727 -0.00635) (xy 22.8727 -2.7559) (xy -22.8727 -2.7559) (xy -22.8727 2.7559)
				(xy 1.905 2.7559) (xy 1.905 3.5179) (xy 8.255 3.5179) (xy 8.255 2.7559) (xy 22.8727 2.7559) (xy 22.8727 0.00635)
				(xy 23.6728 0.00635) (xy 23.6728 3.2639) (xy 8.763 3.2639) (xy 8.763 4.5466)
			)
			(stroke
				(width 0)
				(type default)
			)
			(fill no)
			(layer "F.CrtYd")
		)
		(fp_poly
			(pts
				(xy 1.397 4.5466) (xy 1.397 3.2639) (xy -23.6728 3.2639) (xy -23.6728 -3.5052) (xy 23.6728 -3.5052)
				(xy 23.6728 3.2639) (xy 8.763 3.2639) (xy 8.763 4.5466)
			)
			(stroke
				(width 0)
				(type default)
			)
			(fill no)
			(layer "F.Fab")
		)
		(pad "" np_thru_hole circle
			(at -18.874994 0 270)
			(size 0.254 0.254)
			(drill 1.3462)
			(layers "*.Cu" "*.Mask")
			(clearance 0.9017)
			(thermal_gap 0.9017)
		)
		(pad "" np_thru_hole circle
			(at 18.874994 0 270)
			(size 0.254 0.254)
			(drill 0.9398)
			(layers "*.Cu" "*.Mask")
			(clearance 0.6985)
			(thermal_gap 0.6985)
		)
		(pad "G1" smd rect
			(at 21.874988 0 270)
			(size 2.5908 2.5908)
			(layers "F.Cu" "F.Mask" "F.Paste")
			(net "GND")
		)
		(pad "G2" smd rect
			(at -21.874988 0 270)
			(size 2.5908 2.5908)
			(layers "F.Cu" "F.Mask" "F.Paste")
			(net "GND")
		)
		(pad "P1" smd rect
			(at 1.905 -1.82499 270)
			(size 0.6096 2.3622)
			(layers "F.Cu" "F.Mask" "F.Paste")
			(net "Net_2051")
		)
		(pad "P2" smd rect
			(at 0.635 -1.82499 270)
			(size 0.6096 2.3622)
			(layers "F.Cu" "F.Mask" "F.Paste")
			(net "Net_2052")
		)
		(pad "P3" smd rect
			(at -0.635 -1.82499 270)
			(size 0.6096 2.3622)
			(layers "F.Cu" "F.Mask" "F.Paste")
			(net "Net_2053")
		)
		(pad "P4" smd rect
			(at -1.905 -1.82499 270)
			(size 0.6096 2.3622)
			(layers "F.Cu" "F.Mask" "F.Paste")
			(net "GND")
		)
		(pad "P5" smd rect
			(at -3.175 -1.82499 270)
			(size 0.6096 2.3622)
			(layers "F.Cu" "F.Mask" "F.Paste")
			(net "HDD_PRSNT_31")
		)
		(pad "P6" smd rect
			(at -4.445 -1.82499 270)
			(size 0.6096 2.3622)
			(layers "F.Cu" "F.Mask" "F.Paste")
			(net "GND")
		)
		(pad "P7" smd rect
			(at -5.715 -1.82499 270)
			(size 0.6096 2.3622)
			(layers "F.Cu" "F.Mask" "F.Paste")
			(net "5V_PRE_31")
		)
		(pad "P8" smd rect
			(at -6.985 -1.82499 270)
			(size 0.6096 2.3622)
			(layers "F.Cu" "F.Mask" "F.Paste")
			(net "P5V_HDD31")
		)
		(pad "P9" smd rect
			(at -8.255 -1.82499 270)
			(size 0.6096 2.3622)
			(layers "F.Cu" "F.Mask" "F.Paste")
			(net "P5V_HDD31")
		)
		(pad "P10" smd rect
			(at -9.525 -1.82499 270)
			(size 0.6096 2.3622)
			(layers "F.Cu" "F.Mask" "F.Paste")
			(net "GND")
		)
		(pad "P11" smd rect
			(at -10.795 -1.82499 270)
			(size 0.6096 2.3622)
			(layers "F.Cu" "F.Mask" "F.Paste")
			(net "ACT_HDD_31")
		)
		(pad "P12" smd rect
			(at -12.065 -1.82499 270)
			(size 0.6096 2.3622)
			(layers "F.Cu" "F.Mask" "F.Paste")
			(net "GND")
		)
		(pad "P13" smd rect
			(at -13.335 -1.82499 270)
			(size 0.6096 2.3622)
			(layers "F.Cu" "F.Mask" "F.Paste")
			(net "12V_PRE_31")
		)
		(pad "P14" smd rect
			(at -14.605 -1.82499 270)
			(size 0.6096 2.3622)
			(layers "F.Cu" "F.Mask" "F.Paste")
			(net "P12V_HDD31")
		)
		(pad "P15" smd rect
			(at -15.875 -1.82499 270)
			(size 0.6096 2.3622)
			(layers "F.Cu" "F.Mask" "F.Paste")
			(net "P12V_HDD31")
		)
		(pad "S1" smd rect
			(at 15.875 -1.82499 270)
			(size 0.6096 2.3622)
			(layers "F.Cu" "F.Mask" "F.Paste")
			(net "GND")
		)
		(pad "S2" smd rect
			(at 14.605 -1.82499 270)
			(size 0.6096 2.3622)
			(layers "F.Cu" "F.Mask" "F.Paste")
			(net "SAS_HDD_RX_P31")
		)
		(pad "S3" smd rect
			(at 13.335 -1.82499 270)
			(size 0.6096 2.3622)
			(layers "F.Cu" "F.Mask" "F.Paste")
			(net "SAS_HDD_RX_N31")
		)
		(pad "S4" smd rect
			(at 12.065 -1.82499 270)
			(size 0.6096 2.3622)
			(layers "F.Cu" "F.Mask" "F.Paste")
			(net "GND")
		)
		(pad "S5" smd rect
			(at 10.795 -1.82499 270)
			(size 0.6096 2.3622)
			(layers "F.Cu" "F.Mask" "F.Paste")
			(net "PHY_DRV_A_TO_SCC_A_31_DN")
		)
		(pad "S6" smd rect
			(at 9.525 -1.82499 270)
			(size 0.6096 2.3622)
			(layers "F.Cu" "F.Mask" "F.Paste")
			(net "PHY_DRV_A_TO_SCC_A_31_DP")
		)
		(pad "S7" smd rect
			(at 8.255 -1.82499 270)
			(size 0.6096 2.3622)
			(layers "F.Cu" "F.Mask" "F.Paste")
			(net "GND")
		)
		(pad "S8" smd rect
			(at 7.480046 2.845054 270)
			(size 0.508 2.3622)
			(layers "F.Cu" "F.Mask" "F.Paste")
			(net "GND")
		)
		(pad "S9" smd rect
			(at 6.679946 2.845054 270)
			(size 0.508 2.3622)
			(layers "F.Cu" "F.Mask" "F.Paste")
			(net "Net_470")
		)
		(pad "S10" smd rect
			(at 5.8801 2.845054 270)
			(size 0.508 2.3622)
			(layers "F.Cu" "F.Mask" "F.Paste")
			(net "Net_362")
		)
		(pad "S11" smd rect
			(at 5.08 2.845054 270)
			(size 0.508 2.3622)
			(layers "F.Cu" "F.Mask" "F.Paste")
			(net "GND")
		)
		(pad "S12" smd rect
			(at 4.2799 2.845054 270)
			(size 0.508 2.3622)
			(layers "F.Cu" "F.Mask" "F.Paste")
			(net "Net_398")
		)
		(pad "S13" smd rect
			(at 3.480054 2.845054 270)
			(size 0.508 2.3622)
			(layers "F.Cu" "F.Mask" "F.Paste")
			(net "Net_434")
		)
		(pad "S14" smd rect
			(at 2.679954 2.845054 270)
			(size 0.508 2.3622)
			(layers "F.Cu" "F.Mask" "F.Paste")
			(net "GND")
		)
		(zone
			(layer "F.Cu")
			(hatch none 0.5)
			(connect_pads
				(clearance 0)
			)
			(min_thickness 0.25)
			(keepout
				(tracks not_allowed)
				(vias allowed)
				(pads allowed)
				(copperpour not_allowed)
				(footprints allowed)
			)
			(placement
				(enabled no)
				(sheetname "")
			)
			(fill
				(thermal_gap 0.5)
				(thermal_bridge_width 0.5)
				(island_removal_mode 0)
			)
			(polygon
				(pts
					(xy 360.757724 -74.648568) (xy 353.683824 -74.648568) (xy 353.683824 -81.582768) (xy 354.788724 -81.582768)
					(xy 354.788724 -77.467968) (xy 359.411524 -77.467968) (xy 359.411524 -81.582768) (xy 360.757724 -81.582768)
				)
			)
		)
		(zone
			(layer "F.Cu")
			(hatch none 0.5)
			(connect_pads
				(clearance 0)
			)
			(min_thickness 0.25)
			(keepout
				(tracks allowed)
				(vias not_allowed)
				(pads allowed)
				(copperpour not_allowed)
				(footprints allowed)
			)
			(placement
				(enabled no)
				(sheetname "")
			)
			(fill
				(thermal_gap 0.5)
				(thermal_bridge_width 0.5)
				(island_removal_mode 0)
			)
			(polygon
				(pts
					(xy 360.757724 -74.648568) (xy 353.683824 -74.648568) (xy 353.683824 -81.582768) (xy 354.788724 -81.582768)
					(xy 354.788724 -77.467968) (xy 359.411524 -77.467968) (xy 359.411524 -81.582768) (xy 360.757724 -81.582768)
				)
			)
		)
		(zone
			(layer "F.Cu")
			(hatch none 0.5)
			(connect_pads
				(clearance 0)
			)
			(min_thickness 0.25)
			(keepout
				(tracks not_allowed)
				(vias allowed)
				(pads allowed)
				(copperpour not_allowed)
				(footprints allowed)
			)
			(placement
				(enabled no)
				(sheetname "")
			)
			(fill
				(thermal_gap 0.5)
				(thermal_bridge_width 0.5)
				(island_removal_mode 0)
			)
			(polygon
				(pts
					(xy 360.757724 -41.171368) (xy 353.683824 -41.171368) (xy 353.683824 -34.237168) (xy 354.788724 -34.237168)
					(xy 354.788724 -38.351968) (xy 359.411524 -38.351968) (xy 359.411524 -34.237168) (xy 360.757724 -34.237168)
				)
			)
		)
		(zone
			(layer "F.Cu")
			(hatch none 0.5)
			(connect_pads
				(clearance 0)
			)
			(min_thickness 0.25)
			(keepout
				(tracks allowed)
				(vias not_allowed)
				(pads allowed)
				(copperpour not_allowed)
				(footprints allowed)
			)
			(placement
				(enabled no)
				(sheetname "")
			)
			(fill
				(thermal_gap 0.5)
				(thermal_bridge_width 0.5)
				(island_removal_mode 0)
			)
			(polygon
				(pts
					(xy 360.757724 -41.171368) (xy 353.683824 -41.171368) (xy 353.683824 -34.237168) (xy 354.788724 -34.237168)
					(xy 354.788724 -38.351968) (xy 359.411524 -38.351968) (xy 359.411524 -34.237168) (xy 360.757724 -34.237168)
				)
			)
		)
		(zone
			(layers "F.Cu" "B.Cu" "In1.Cu" "In2.Cu" "In3.Cu" "In4.Cu" "In5.Cu" "In6.Cu"
				"In7.Cu" "In8.Cu" "In9.Cu" "In10.Cu"
			)
			(hatch none 0.5)
			(connect_pads
				(clearance 0)
			)
			(min_thickness 0.25)
			(keepout
				(tracks not_allowed)
				(vias allowed)
				(pads allowed)
				(copperpour not_allowed)
				(footprints allowed)
			)
			(placement
				(enabled no)
				(sheetname "")
			)
			(fill
				(thermal_gap 0.5)
				(thermal_bridge_width 0.5)
				(island_removal_mode 0)
			)
			(polygon
				(pts
					(arc
						(start 357.874824 -39.034974)
						(mid 356.325424 -39.034974)
						(end 357.874824 -39.034974)
					)
				)
			)
		)
		(zone
			(layers "F.Cu" "B.Cu" "In1.Cu" "In2.Cu" "In3.Cu" "In4.Cu" "In5.Cu" "In6.Cu"
				"In7.Cu" "In8.Cu" "In9.Cu" "In10.Cu"
			)
			(hatch none 0.5)
			(connect_pads
				(clearance 0)
			)
			(min_thickness 0.25)
			(keepout
				(tracks not_allowed)
				(vias allowed)
				(pads allowed)
				(copperpour not_allowed)
				(footprints allowed)
			)
			(placement
				(enabled no)
				(sheetname "")
			)
			(fill
				(thermal_gap 0.5)
				(thermal_bridge_width 0.5)
				(island_removal_mode 0)
			)
			(polygon
				(pts
					(arc
						(start 358.078024 -76.784962)
						(mid 356.122224 -76.784962)
						(end 358.078024 -76.784962)
					)
				)
			)
		)
	)
	(footprint ""
		(layer "F.Cu")
		(at 153.712672 -131.18973 90)
		(property "Reference" "Q219"
			(at 0 0 90)
			(layer "F.SilkS")
			(hide yes)
			(effects
				(font
					(size 1.27 1.27)
				)
			)
		)
		(property "Value" "MMBT3904-3-GP"
			(at 0.10287 -10.29843 90)
			(unlocked yes)
			(layer "F.Fab")
			(hide yes)
			(effects
				(font
					(size 1.016 1.016)
					(thickness 0.1524)
				)
			)
		)
		(property "Device Type" "SOT23CBE2D4H44"
			(at 0.10287 -12.20343 90)
			(unlocked yes)
			(layer "F.Fab")
			(hide yes)
			(effects
				(font
					(size 1.016 1.016)
					(thickness 0.1524)
				)
			)
		)
		(duplicate_pad_numbers_are_jumpers no)
		(fp_line
			(start 1.651 -1.778)
			(end -1.651 -1.778)
			(stroke
				(width 0.1524)
				(type default)
			)
			(layer "F.SilkS")
		)
		(fp_line
			(start -1.651 -1.778)
			(end -1.651 1.778)
			(stroke
				(width 0.1524)
				(type default)
			)
			(layer "F.SilkS")
		)
		(fp_line
			(start 1.651 1.778)
			(end 1.651 -1.778)
			(stroke
				(width 0.1524)
				(type default)
			)
			(layer "F.SilkS")
		)
		(fp_line
			(start -1.651 1.778)
			(end 1.651 1.778)
			(stroke
				(width 0.1524)
				(type default)
			)
			(layer "F.SilkS")
		)
		(fp_poly
			(pts
				(xy -1.778 1.8796) (xy -1.778 -1.8796) (xy 1.778 -1.8796) (xy 1.778 1.8796)
			)
			(stroke
				(width 0)
				(type default)
			)
			(fill no)
			(layer "F.CrtYd")
		)
		(fp_poly
			(pts
				(xy -1.778 1.8796) (xy -1.778 -1.8796) (xy 1.778 -1.8796) (xy 1.778 1.8796)
			)
			(stroke
				(width 0)
				(type default)
			)
			(fill no)
			(layer "F.Fab")
		)
		(pad "B" smd custom
			(at -0.98425 0.9525 90)
			(size 0.1905 0.1905)
			(layers "F.Cu" "F.Mask" "F.Paste")
			(net "MB0_TEMP_B")
			(options
				(clearance outline)
				(anchor circle)
			)
			(primitives
				(gr_poly
					(pts
						(arc
							(start -0.1778 0.5715)
							(mid -0.321484 0.511984)
							(end -0.381 0.3683)
						)
						(arc
							(start -0.381 -0.3683)
							(mid -0.321484 -0.511984)
							(end -0.1778 -0.5715)
						)
						(arc
							(start 0.1778 -0.5715)
							(mid 0.321484 -0.511984)
							(end 0.381 -0.3683)
						)
						(arc
							(start 0.381 0.3683)
							(mid 0.321484 0.511984)
							(end 0.1778 0.5715)
						)
					)
					(width 0)
					(fill yes)
				)
			)
		)
		(pad "C" smd custom
			(at 0 -0.9525 90)
			(size 0.1905 0.1905)
			(layers "F.Cu" "F.Mask" "F.Paste")
			(net "MB0_TEMP_B")
			(options
				(clearance outline)
				(anchor circle)
			)
			(primitives
				(gr_poly
					(pts
						(arc
							(start -0.1778 0.5715)
							(mid -0.321484 0.511984)
							(end -0.381 0.3683)
						)
						(arc
							(start -0.381 -0.3683)
							(mid -0.321484 -0.511984)
							(end -0.1778 -0.5715)
						)
						(arc
							(start 0.1778 -0.5715)
							(mid 0.321484 -0.511984)
							(end 0.381 -0.3683)
						)
						(arc
							(start 0.381 0.3683)
							(mid 0.321484 0.511984)
							(end 0.1778 0.5715)
						)
					)
					(width 0)
					(fill yes)
				)
			)
		)
		(pad "E" smd custom
			(at 0.98425 0.9525 90)
			(size 0.1905 0.1905)
			(layers "F.Cu" "F.Mask" "F.Paste")
			(net "MB0_TEMP_E")
			(options
				(clearance outline)
				(anchor circle)
			)
			(primitives
				(gr_poly
					(pts
						(arc
							(start -0.1778 0.5715)
							(mid -0.321484 0.511984)
							(end -0.381 0.3683)
						)
						(arc
							(start -0.381 -0.3683)
							(mid -0.321484 -0.511984)
							(end -0.1778 -0.5715)
						)
						(arc
							(start 0.1778 -0.5715)
							(mid 0.321484 -0.511984)
							(end 0.381 -0.3683)
						)
						(arc
							(start 0.381 0.3683)
							(mid 0.321484 0.511984)
							(end 0.1778 0.5715)
						)
					)
					(width 0)
					(fill yes)
				)
			)
		)
	)
	(footprint ""
		(layer "F.Cu")
		(at 47.09033 -149.115018 90)
		(property "Reference" "R1234"
			(at 0 0 90)
			(layer "F.SilkS")
			(hide yes)
			(effects
				(font
					(size 1.27 1.27)
				)
			)
		)
		(property "Value" "100KR2F-L1-GP"
			(at 0.064008 -3.993896 90)
			(unlocked yes)
			(layer "F.Fab")
			(hide yes)
			(effects
				(font
					(size 1.016 1.016)
					(thickness 0.1524)
				)
			)
		)
		(property "Device Type" "R402H16"
			(at 0.064008 -5.517896 90)
			(unlocked yes)
			(layer "F.Fab")
			(hide yes)
			(effects
				(font
					(size 1.016 1.016)
					(thickness 0.1524)
				)
			)
		)
		(duplicate_pad_numbers_are_jumpers no)
		(fp_line
			(start 0.508 -0.9398)
			(end -0.508 -0.9398)
			(stroke
				(width 0.1524)
				(type default)
			)
			(layer "F.SilkS")
		)
		(fp_line
			(start -0.508 -0.9398)
			(end -0.508 0.9398)
			(stroke
				(width 0.1524)
				(type default)
			)
			(layer "F.SilkS")
		)
		(fp_rect
			(start -0.508 0.9398)
			(end 0.508 -0.9398)
			(stroke
				(width 0)
				(type default)
			)
			(fill no)
			(layer "F.CrtYd")
		)
		(fp_rect
			(start -0.508 0.9398)
			(end 0.508 -0.9398)
			(stroke
				(width 0)
				(type default)
			)
			(fill no)
			(layer "F.Fab")
		)
		(pad "1" smd custom
			(at 0 -0.4445 90)
			(size 0.1397 0.1397)
			(layers "F.Cu" "F.Mask" "F.Paste")
			(net "AGND_P5V_B")
			(options
				(clearance outline)
				(anchor circle)
			)
			(primitives
				(gr_poly
					(pts
						(arc
							(start -0.1778 -0.2794)
							(mid -0.249642 -0.249642)
							(end -0.2794 -0.1778)
						)
						(arc
							(start -0.2794 0.1778)
							(mid -0.249642 0.249642)
							(end -0.1778 0.2794)
						)
						(arc
							(start 0.1778 0.2794)
							(mid 0.249642 0.249642)
							(end 0.2794 0.1778)
						)
						(arc
							(start 0.2794 -0.1778)
							(mid 0.249642 -0.249642)
							(end 0.1778 -0.2794)
						)
					)
					(width 0)
					(fill yes)
				)
			)
		)
		(pad "2" smd custom
			(at 0 0.4445 90)
			(size 0.1397 0.1397)
			(layers "F.Cu" "F.Mask" "F.Paste")
			(net "P5V_B_MODE")
			(options
				(clearance outline)
				(anchor circle)
			)
			(primitives
				(gr_poly
					(pts
						(arc
							(start -0.1778 -0.2794)
							(mid -0.249642 -0.249642)
							(end -0.2794 -0.1778)
						)
						(arc
							(start -0.2794 0.1778)
							(mid -0.249642 0.249642)
							(end -0.1778 0.2794)
						)
						(arc
							(start 0.1778 0.2794)
							(mid 0.249642 0.249642)
							(end 0.2794 0.1778)
						)
						(arc
							(start 0.2794 -0.1778)
							(mid 0.249642 -0.249642)
							(end 0.1778 -0.2794)
						)
					)
					(width 0)
					(fill yes)
				)
			)
		)
	)
)
